(kicad_pcb
	(version 20260206)
	(generator "pcbnew")
	(generator_version "10.0")
	(general
		(thickness 1.6)
		(legacy_teardrops no)
	)
	(paper "A4")
	(title_block
		(title "04192023_DAF0TMB3IC0_F0TG_MB_C_brd_V02_OCP.brd")
		(comment 1 "Grand Teton / footprints 1940-1945 of 8354")
	)
	(layers
		(0 "F.Cu" signal "TOP")
		(4 "In1.Cu" signal "GND")
		(6 "In2.Cu" signal "IN1")
		(8 "In3.Cu" signal "GND1")
		(10 "In4.Cu" signal "IN2")
		(12 "In5.Cu" signal "GND2")
		(14 "In6.Cu" signal "IN3")
		(16 "In7.Cu" signal "GND3")
		(18 "In8.Cu" signal "VCC")
		(20 "In9.Cu" signal "VCC1")
		(22 "In10.Cu" signal "GND4")
		(24 "In11.Cu" signal "IN4")
		(26 "In12.Cu" signal "GND5")
		(28 "In13.Cu" signal "IN5")
		(30 "In14.Cu" signal "GND6")
		(32 "In15.Cu" signal "IN6")
		(34 "In16.Cu" signal "GND7")
		(2 "B.Cu" signal "BOTTOM")
		(9 "F.Adhes" user "F.Adhesive")
		(11 "B.Adhes" user "B.Adhesive")
		(13 "F.Paste" user "Package Geometry/Pastemask Top")
		(15 "B.Paste" user "Package Geometry/Pastemask Bottom")
		(5 "F.SilkS" user "Ref Des/Silkscreen Top")
		(7 "B.SilkS" user "Ref Des/Silkscreen Bottom")
		(1 "F.Mask" user "Board Geometry/Soldermask Top")
		(3 "B.Mask" user "Board Geometry/Soldermask Bottom")
		(17 "Dwgs.User" user "User.Drawings")
		(19 "Cmts.User" user "User.Comments")
		(21 "Eco1.User" user "User.Eco1")
		(23 "Eco2.User" user "User.Eco2")
		(25 "Edge.Cuts" user "Board Geometry/Outline")
		(27 "Margin" user)
		(31 "F.CrtYd" user "Package Geometry/Place Bound Top")
		(29 "B.CrtYd" user "Package Geometry/Place Bound Bottom")
		(35 "F.Fab" user "Ref Des/Assembly Top")
		(33 "B.Fab" user "Ref Des/Assembly Bottom")
	)
	(footprint ""
		(layer "F.Cu")
		(at 73.496678 -29.845762 90)
		(property "Reference" "PC2165"
			(at 0 0 90)
			(layer "F.SilkS")
			(hide yes)
			(effects
				(font
					(size 1.27 1.27)
				)
			)
		)
		(property "Value" ""
			(at 0 0 90)
			(layer "F.Fab")
			(effects
				(font
					(size 1.27 1.27)
				)
			)
		)
		(duplicate_pad_numbers_are_jumpers no)
		(fp_line
			(start 0.7874 -0.4064)
			(end 0.7874 0.4064)
			(stroke
				(width 0.1524)
				(type default)
			)
			(layer "F.SilkS")
		)
		(fp_line
			(start -0.7874 -0.4064)
			(end 0.7874 -0.4064)
			(stroke
				(width 0.1524)
				(type default)
			)
			(layer "F.SilkS")
		)
		(fp_line
			(start 0.7874 0.4064)
			(end -0.7874 0.4064)
			(stroke
				(width 0.1524)
				(type default)
			)
			(layer "F.SilkS")
		)
		(fp_line
			(start -0.7874 0.4064)
			(end -0.7874 -0.4064)
			(stroke
				(width 0.1524)
				(type default)
			)
			(layer "F.SilkS")
		)
		(fp_line
			(start -0.12065 -0.305054)
			(end -0.12065 -0.2794)
			(stroke
				(width 0.1)
				(type default)
			)
			(layer "F.Fab")
		)
		(fp_line
			(start -0.67945 -0.305054)
			(end -0.12065 -0.305054)
			(stroke
				(width 0.1)
				(type default)
			)
			(layer "F.Fab")
		)
		(fp_line
			(start 0.67945 -0.3048)
			(end 0.67945 0.3048)
			(stroke
				(width 0.1)
				(type default)
			)
			(layer "F.Fab")
		)
		(fp_line
			(start 0.12065 -0.3048)
			(end 0.67945 -0.3048)
			(stroke
				(width 0.1)
				(type default)
			)
			(layer "F.Fab")
		)
		(fp_line
			(start 0.12065 -0.2794)
			(end 0.12065 -0.3048)
			(stroke
				(width 0.1)
				(type default)
			)
			(layer "F.Fab")
		)
		(fp_line
			(start -0.12065 -0.2794)
			(end 0.12065 -0.2794)
			(stroke
				(width 0.1)
				(type default)
			)
			(layer "F.Fab")
		)
		(fp_line
			(start 0.120396 0.2794)
			(end -0.12065 0.2794)
			(stroke
				(width 0.1)
				(type default)
			)
			(layer "F.Fab")
		)
		(fp_line
			(start -0.12065 0.2794)
			(end -0.12065 0.3048)
			(stroke
				(width 0.1)
				(type default)
			)
			(layer "F.Fab")
		)
		(fp_line
			(start 0.67945 0.3048)
			(end 0.120396 0.3048)
			(stroke
				(width 0.1)
				(type default)
			)
			(layer "F.Fab")
		)
		(fp_line
			(start 0.120396 0.3048)
			(end 0.120396 0.2794)
			(stroke
				(width 0.1)
				(type default)
			)
			(layer "F.Fab")
		)
		(fp_line
			(start -0.12065 0.3048)
			(end -0.67945 0.3048)
			(stroke
				(width 0.1)
				(type default)
			)
			(layer "F.Fab")
		)
		(fp_line
			(start -0.67945 0.3048)
			(end -0.67945 -0.305054)
			(stroke
				(width 0.1)
				(type default)
			)
			(layer "F.Fab")
		)
		(pad "1" smd circle
			(at -0.40005 0 90)
			(size 0 0)
			(layers "F.Cu" "F.Mask" "F.Paste")
			(net "P12V_AUX")
		)
		(pad "2" smd circle
			(at 0.40005 0 90)
			(size 0 0)
			(layers "F.Cu" "F.Mask" "F.Paste")
			(net "GND")
		)
	)
	(footprint ""
		(layer "F.Cu")
		(at 366.36579 -393.96416)
		(property "Reference" "R1112"
			(at 0 0 0)
			(layer "F.SilkS")
			(hide yes)
			(effects
				(font
					(size 1.27 1.27)
				)
			)
		)
		(property "Value" ""
			(at 0 0 0)
			(layer "F.Fab")
			(effects
				(font
					(size 1.27 1.27)
				)
			)
		)
		(duplicate_pad_numbers_are_jumpers no)
		(fp_line
			(start -0.32512 -0.175006)
			(end 0.32512 -0.175006)
			(stroke
				(width 0.1)
				(type default)
			)
			(layer "F.Fab")
		)
		(fp_line
			(start -0.32512 0.175006)
			(end -0.32512 -0.175006)
			(stroke
				(width 0.1)
				(type default)
			)
			(layer "F.Fab")
		)
		(fp_line
			(start 0.32512 -0.175006)
			(end 0.32512 0.175006)
			(stroke
				(width 0.1)
				(type default)
			)
			(layer "F.Fab")
		)
		(fp_line
			(start 0.32512 0.175006)
			(end -0.32512 0.175006)
			(stroke
				(width 0.1)
				(type default)
			)
			(layer "F.Fab")
		)
		(pad "1" smd rect
			(at -0.2667 0)
			(size 0.3048 0.381)
			(layers "F.Cu" "F.Mask" "F.Paste")
			(net "GPIO2_RT_CPU0_P3")
		)
		(pad "2" smd rect
			(at 0.2667 0 180)
			(size 0.3048 0.381)
			(layers "F.Cu" "F.Mask" "F.Paste")
			(net "GND")
		)
	)
	(footprint ""
		(layer "F.Cu")
		(at 440.687968 -94.077536 180)
		(property "Reference" "U266"
			(at 0.221996 2.912872 0)
			(unlocked yes)
			(layer "F.SilkS")
			(effects
				(font
					(size 0.7874 0.5842)
					(thickness 0.1524)
				)
			)
		)
		(property "Value" ""
			(at 0 0 180)
			(layer "F.Fab")
			(effects
				(font
					(size 1.27 1.27)
				)
			)
		)
		(duplicate_pad_numbers_are_jumpers no)
		(fp_line
			(start 1.500124 1.500124)
			(end 1.004062 1.500124)
			(stroke
				(width 0.1524)
				(type default)
			)
			(layer "F.SilkS")
		)
		(fp_line
			(start 1.500124 1.004062)
			(end 1.500124 1.500124)
			(stroke
				(width 0.1524)
				(type default)
			)
			(layer "F.SilkS")
		)
		(fp_line
			(start 1.500124 -1.500124)
			(end 1.500124 -1.004062)
			(stroke
				(width 0.1524)
				(type default)
			)
			(layer "F.SilkS")
		)
		(fp_line
			(start 1.004062 -1.500124)
			(end 1.500124 -1.500124)
			(stroke
				(width 0.1524)
				(type default)
			)
			(layer "F.SilkS")
		)
		(fp_line
			(start -1.004062 1.500124)
			(end -1.500124 1.500124)
			(stroke
				(width 0.1524)
				(type default)
			)
			(layer "F.SilkS")
		)
		(fp_line
			(start -1.500124 1.500124)
			(end -1.500124 1.004062)
			(stroke
				(width 0.1524)
				(type default)
			)
			(layer "F.SilkS")
		)
		(fp_line
			(start -1.500124 -1.004062)
			(end -1.500124 -1.500124)
			(stroke
				(width 0.1524)
				(type default)
			)
			(layer "F.SilkS")
		)
		(fp_line
			(start -1.500124 -1.500124)
			(end -1.004062 -1.500124)
			(stroke
				(width 0.1524)
				(type default)
			)
			(layer "F.SilkS")
		)
		(fp_poly
			(pts
				(xy -2.242312 -0.54102) (xy -2.242312 -0.999744) (xy -1.783588 -0.770382)
			)
			(stroke
				(width 0)
				(type default)
			)
			(fill yes)
			(layer "F.SilkS")
		)
		(fp_line
			(start 1.500124 1.500124)
			(end -1.500124 1.500124)
			(stroke
				(width 0.1)
				(type default)
			)
			(layer "F.Fab")
		)
		(fp_line
			(start 1.500124 -1.500124)
			(end 1.500124 1.500124)
			(stroke
				(width 0.1)
				(type default)
			)
			(layer "F.Fab")
		)
		(fp_line
			(start -1.500124 1.500124)
			(end -1.500124 -1.500124)
			(stroke
				(width 0.1)
				(type default)
			)
			(layer "F.Fab")
		)
		(fp_line
			(start -1.500124 -1.500124)
			(end 1.500124 -1.500124)
			(stroke
				(width 0.1)
				(type default)
			)
			(layer "F.Fab")
		)
		(fp_poly
			(pts
				(xy -2.847848 -1.258062) (xy -2.847848 -0.242062) (xy -1.831848 -0.750062)
			)
			(stroke
				(width 0)
				(type default)
			)
			(fill yes)
			(layer "F.Fab")
		)
		(pad "1" smd rect
			(at -1.400048 -0.750062 90)
			(size 0.2286 0.6096)
			(layers "F.Cu" "F.Mask" "F.Paste")
			(net "INA230_1_A1")
		)
		(pad "2" smd rect
			(at -1.400048 -0.249936 90)
			(size 0.2286 0.6096)
			(layers "F.Cu" "F.Mask" "F.Paste")
			(net "INA230_1_A0")
		)
		(pad "3" smd rect
			(at -1.400048 0.249936 90)
			(size 0.2286 0.6096)
			(layers "F.Cu" "F.Mask" "F.Paste")
			(net "OCP_SFF_P3V3_ADC_ALERT_R")
		)
		(pad "4" smd rect
			(at -1.400048 0.750062 90)
			(size 0.2286 0.6096)
			(layers "F.Cu" "F.Mask" "F.Paste")
			(net "SMB_INA230_1_3V3AUX_SDA_R1")
		)
		(pad "5" smd rect
			(at -0.750062 1.400048 180)
			(size 0.2286 0.6096)
			(layers "F.Cu" "F.Mask" "F.Paste")
			(net "SMB_INA230_1_3V3AUX_SCL_R1")
		)
		(pad "6" smd rect
			(at -0.249936 1.400048 180)
			(size 0.2286 0.6096)
			(layers "F.Cu" "F.Mask" "F.Paste")
			(net "NC_INA230_1_NC0")
		)
		(pad "7" smd rect
			(at 0.249936 1.400048 180)
			(size 0.2286 0.6096)
			(layers "F.Cu" "F.Mask" "F.Paste")
			(net "NC_INA230_1_NC1")
		)
		(pad "8" smd rect
			(at 0.750062 1.400048 180)
			(size 0.2286 0.6096)
			(layers "F.Cu" "F.Mask" "F.Paste")
			(net "NC_INA230_1_NC2")
		)
		(pad "9" smd rect
			(at 1.400048 0.750062 90)
			(size 0.2286 0.6096)
			(layers "F.Cu" "F.Mask" "F.Paste")
			(net "P3V3_AUX")
		)
		(pad "10" smd rect
			(at 1.400048 0.249936 90)
			(size 0.2286 0.6096)
			(layers "F.Cu" "F.Mask" "F.Paste")
			(net "GND")
		)
		(pad "11" smd rect
			(at 1.400048 -0.249936 90)
			(size 0.2286 0.6096)
			(layers "F.Cu" "F.Mask" "F.Paste")
			(net "P3V3_OCP_SFF_R")
		)
		(pad "12" smd rect
			(at 1.400048 -0.750062 90)
			(size 0.2286 0.6096)
			(layers "F.Cu" "F.Mask" "F.Paste")
			(net "VSENSE_P3V3_INA230_1_INN")
		)
		(pad "13" smd rect
			(at 0.750062 -1.400048 180)
			(size 0.2286 0.6096)
			(layers "F.Cu" "F.Mask" "F.Paste")
			(net "VSENSE_P3V3_INA230_1_INP")
		)
		(pad "14" smd rect
			(at 0.249936 -1.400048 180)
			(size 0.2286 0.6096)
			(layers "F.Cu" "F.Mask" "F.Paste")
			(net "NC_INA230_1_NC3")
		)
		(pad "15" smd rect
			(at -0.249936 -1.400048 180)
			(size 0.2286 0.6096)
			(layers "F.Cu" "F.Mask" "F.Paste")
			(net "NC_INA230_1_NC4")
		)
		(pad "16" smd rect
			(at -0.750062 -1.400048 180)
			(size 0.2286 0.6096)
			(layers "F.Cu" "F.Mask" "F.Paste")
			(net "NC_INA230_1_NC5")
		)
		(pad "TH" smd rect
			(at 0 0 180)
			(size 1.7018 1.7018)
			(layers "F.Cu" "F.Mask" "F.Paste")
			(net "GND")
		)
		(zone
			(layer "F.Cu")
			(hatch none 0.5)
			(connect_pads
				(clearance 0)
			)
			(min_thickness 0.25)
			(keepout
				(tracks not_allowed)
				(vias allowed)
				(pads allowed)
				(copperpour not_allowed)
				(footprints allowed)
			)
			(placement
				(enabled no)
				(sheetname "")
			)
			(fill
				(thermal_gap 0.5)
				(thermal_bridge_width 0.5)
				(island_removal_mode 0)
			)
			(polygon
				(pts
					(xy 441.732416 -94.052136) (xy 441.732416 -93.033088) (xy 439.64352 -93.033088) (xy 439.64352 -95.121984)
					(xy 441.732416 -95.121984) (xy 441.732416 -94.077536) (xy 441.589668 -94.077536) (xy 441.589668 -94.979236)
					(xy 439.786268 -94.979236) (xy 439.786268 -93.175836) (xy 441.589668 -93.175836) (xy 441.589668 -94.052136)
				)
			)
		)
	)
	(footprint ""
		(layer "F.Cu")
		(at 259.842 -143.764)
		(property "Reference" "R127"
			(at 0 0 0)
			(layer "F.SilkS")
			(hide yes)
			(effects
				(font
					(size 1.27 1.27)
				)
			)
		)
		(property "Value" ""
			(at 0 0 0)
			(layer "F.Fab")
			(effects
				(font
					(size 1.27 1.27)
				)
			)
		)
		(duplicate_pad_numbers_are_jumpers no)
		(fp_line
			(start -0.7874 -0.4064)
			(end 0.7874 -0.4064)
			(stroke
				(width 0.1524)
				(type default)
			)
			(layer "F.SilkS")
		)
		(fp_line
			(start -0.7874 0.4064)
			(end -0.7874 -0.4064)
			(stroke
				(width 0.1524)
				(type default)
			)
			(layer "F.SilkS")
		)
		(fp_line
			(start 0.7874 -0.4064)
			(end 0.7874 0.4064)
			(stroke
				(width 0.1524)
				(type default)
			)
			(layer "F.SilkS")
		)
		(fp_line
			(start 0.7874 0.4064)
			(end -0.7874 0.4064)
			(stroke
				(width 0.1524)
				(type default)
			)
			(layer "F.SilkS")
		)
		(fp_line
			(start -0.67945 -0.305054)
			(end -0.12065 -0.305054)
			(stroke
				(width 0.1)
				(type default)
			)
			(layer "F.Fab")
		)
		(fp_line
			(start -0.67945 0.3048)
			(end -0.67945 -0.305054)
			(stroke
				(width 0.1)
				(type default)
			)
			(layer "F.Fab")
		)
		(fp_line
			(start -0.12065 -0.305054)
			(end -0.12065 -0.2794)
			(stroke
				(width 0.1)
				(type default)
			)
			(layer "F.Fab")
		)
		(fp_line
			(start -0.12065 -0.2794)
			(end 0.12065 -0.2794)
			(stroke
				(width 0.1)
				(type default)
			)
			(layer "F.Fab")
		)
		(fp_line
			(start -0.12065 0.2794)
			(end -0.12065 0.3048)
			(stroke
				(width 0.1)
				(type default)
			)
			(layer "F.Fab")
		)
		(fp_line
			(start -0.12065 0.3048)
			(end -0.67945 0.3048)
			(stroke
				(width 0.1)
				(type default)
			)
			(layer "F.Fab")
		)
		(fp_line
			(start 0.120396 0.2794)
			(end -0.12065 0.2794)
			(stroke
				(width 0.1)
				(type default)
			)
			(layer "F.Fab")
		)
		(fp_line
			(start 0.120396 0.3048)
			(end 0.120396 0.2794)
			(stroke
				(width 0.1)
				(type default)
			)
			(layer "F.Fab")
		)
		(fp_line
			(start 0.12065 -0.3048)
			(end 0.67945 -0.3048)
			(stroke
				(width 0.1)
				(type default)
			)
			(layer "F.Fab")
		)
		(fp_line
			(start 0.12065 -0.2794)
			(end 0.12065 -0.3048)
			(stroke
				(width 0.1)
				(type default)
			)
			(layer "F.Fab")
		)
		(fp_line
			(start 0.67945 -0.3048)
			(end 0.67945 0.3048)
			(stroke
				(width 0.1)
				(type default)
			)
			(layer "F.Fab")
		)
		(fp_line
			(start 0.67945 0.3048)
			(end 0.120396 0.3048)
			(stroke
				(width 0.1)
				(type default)
			)
			(layer "F.Fab")
		)
		(pad "1" smd circle
			(at -0.40005 0)
			(size 0 0)
			(layers "F.Cu" "F.Mask" "F.Paste")
			(net "P3V3_AUX")
		)
		(pad "2" smd circle
			(at 0.40005 0)
			(size 0 0)
			(layers "F.Cu" "F.Mask" "F.Paste")
			(net "SPI_CPU0_LVC3_SCM_D1")
		)
	)
	(footprint ""
		(layer "F.Cu")
		(at 430.666144 -356.35184 180)
		(property "Reference" "PR134"
			(at 0 0 180)
			(layer "F.SilkS")
			(hide yes)
			(effects
				(font
					(size 1.27 1.27)
				)
			)
		)
		(property "Value" ""
			(at 0 0 180)
			(layer "F.Fab")
			(effects
				(font
					(size 1.27 1.27)
				)
			)
		)
		(duplicate_pad_numbers_are_jumpers no)
		(fp_line
			(start 0.7874 0.4064)
			(end -0.7874 0.4064)
			(stroke
				(width 0.1524)
				(type default)
			)
			(layer "F.SilkS")
		)
		(fp_line
			(start 0.7874 -0.4064)
			(end 0.7874 0.4064)
			(stroke
				(width 0.1524)
				(type default)
			)
			(layer "F.SilkS")
		)
		(fp_line
			(start -0.7874 0.4064)
			(end -0.7874 -0.4064)
			(stroke
				(width 0.1524)
				(type default)
			)
			(layer "F.SilkS")
		)
		(fp_line
			(start -0.7874 -0.4064)
			(end 0.7874 -0.4064)
			(stroke
				(width 0.1524)
				(type default)
			)
			(layer "F.SilkS")
		)
		(fp_line
			(start 0.67945 0.3048)
			(end 0.120396 0.3048)
			(stroke
				(width 0.1)
				(type default)
			)
			(layer "F.Fab")
		)
		(fp_line
			(start 0.67945 -0.3048)
			(end 0.67945 0.3048)
			(stroke
				(width 0.1)
				(type default)
			)
			(layer "F.Fab")
		)
		(fp_line
			(start 0.12065 -0.2794)
			(end 0.12065 -0.3048)
			(stroke
				(width 0.1)
				(type default)
			)
			(layer "F.Fab")
		)
		(fp_line
			(start 0.12065 -0.3048)
			(end 0.67945 -0.3048)
			(stroke
				(width 0.1)
				(type default)
			)
			(layer "F.Fab")
		)
		(fp_line
			(start 0.120396 0.3048)
			(end 0.120396 0.2794)
			(stroke
				(width 0.1)
				(type default)
			)
			(layer "F.Fab")
		)
		(fp_line
			(start 0.120396 0.2794)
			(end -0.12065 0.2794)
			(stroke
				(width 0.1)
				(type default)
			)
			(layer "F.Fab")
		)
		(fp_line
			(start -0.12065 0.3048)
			(end -0.67945 0.3048)
			(stroke
				(width 0.1)
				(type default)
			)
			(layer "F.Fab")
		)
		(fp_line
			(start -0.12065 0.2794)
			(end -0.12065 0.3048)
			(stroke
				(width 0.1)
				(type default)
			)
			(layer "F.Fab")
		)
		(fp_line
			(start -0.12065 -0.2794)
			(end 0.12065 -0.2794)
			(stroke
				(width 0.1)
				(type default)
			)
			(layer "F.Fab")
		)
		(fp_line
			(start -0.12065 -0.305054)
			(end -0.12065 -0.2794)
			(stroke
				(width 0.1)
				(type default)
			)
			(layer "F.Fab")
		)
		(fp_line
			(start -0.67945 0.3048)
			(end -0.67945 -0.305054)
			(stroke
				(width 0.1)
				(type default)
			)
			(layer "F.Fab")
		)
		(fp_line
			(start -0.67945 -0.305054)
			(end -0.12065 -0.305054)
			(stroke
				(width 0.1)
				(type default)
			)
			(layer "F.Fab")
		)
		(pad "1" smd circle
			(at -0.40005 0 180)
			(size 0 0)
			(layers "F.Cu" "F.Mask" "F.Paste")
			(net "GND")
		)
		(pad "2" smd circle
			(at 0.40005 0 180)
			(size 0 0)
			(layers "F.Cu" "F.Mask" "F.Paste")
			(net "PVDD11_S3_P0_LSET2")
		)
	)
	(footprint ""
		(layer "F.Cu")
		(at 308.528974 -33.351978)
		(property "Reference" "U166"
			(at -1.4224 -1.844548 0)
			(unlocked yes)
			(layer "F.SilkS")
			(effects
				(font
					(size 0.7874 0.5842)
					(thickness 0.1524)
				)
				(justify left)
			)
		)
		(property "Value" ""
			(at 0 0 0)
			(layer "F.Fab")
			(effects
				(font
					(size 1.27 1.27)
				)
			)
		)
		(duplicate_pad_numbers_are_jumpers no)
		(fp_line
			(start -1.335278 -1.100074)
			(end -1.335278 1.100074)
			(stroke
				(width 0.1524)
				(type default)
			)
			(layer "F.SilkS")
		)
		(fp_line
			(start -1.335278 1.100074)
			(end 1.335278 1.100074)
			(stroke
				(width 0.1524)
				(type default)
			)
			(layer "F.SilkS")
		)
		(fp_line
			(start 1.335278 -1.100074)
			(end -1.335278 -1.100074)
			(stroke
				(width 0.1524)
				(type default)
			)
			(layer "F.SilkS")
		)
		(fp_line
			(start 1.335278 1.100074)
			(end 1.335278 -1.100074)
			(stroke
				(width 0.1524)
				(type default)
			)
			(layer "F.SilkS")
		)
		(fp_line
			(start -0.674878 -1.100074)
			(end -0.674878 1.100074)
			(stroke
				(width 0.1)
				(type default)
			)
			(layer "F.Fab")
		)
		(fp_line
			(start -0.674878 1.100074)
			(end 0.674878 1.100074)
			(stroke
				(width 0.1)
				(type default)
			)
			(layer "F.Fab")
		)
		(fp_line
			(start 0.674878 -1.100074)
			(end -0.674878 -1.100074)
			(stroke
				(width 0.1)
				(type default)
			)
			(layer "F.Fab")
		)
		(fp_line
			(start 0.674878 1.100074)
			(end 0.674878 -1.100074)
			(stroke
				(width 0.1)
				(type default)
			)
			(layer "F.Fab")
		)
		(pad "1" smd rect
			(at -0.8001 0.649986 270)
			(size 0.6096 0.8128)
			(layers "F.Cu" "F.Mask" "F.Paste")
			(net "P3V3_STBY_R")
		)
		(pad "2" smd rect
			(at -0.8001 -0.649986 270)
			(size 0.6096 0.8128)
			(layers "F.Cu" "F.Mask" "F.Paste")
			(net "P3V_BAT_R")
		)
		(pad "3" smd rect
			(at 0.8001 0 270)
			(size 0.6096 0.8128)
			(layers "F.Cu" "F.Mask" "F.Paste")
			(net "P3V3_RTC_AUX")
		)
	)
)
